# Thunderbolt to 10GbE adapter — KiCad project settings (.kicad_pro: net classes, design rules, text variables)
{
  "board": {
    "3dviewports": [],
    "design_settings": {
      "defaults": {
        "apply_defaults_to_fp_fields": false,
        "apply_defaults_to_fp_shapes": false,
        "apply_defaults_to_fp_text": false,
        "board_outline_line_width": 0.05,
        "copper_line_width": 0.2,
        "copper_text_italic": false,
        "copper_text_size_h": 1.5,
        "copper_text_size_v": 1.5,
        "copper_text_thickness": 0.3,
        "copper_text_upright": false,
        "courtyard_line_width": 0.05,
        "dimension_precision": 4,
        "dimension_units": 3,
        "dimensions": {
          "arrow_length": 1270000,
          "extension_offset": 500000,
          "keep_text_aligned": true,
          "suppress_zeroes": true,
          "text_position": 0,
          "units_format": 0
        },
        "fab_line_width": 0.1,
        "fab_text_italic": false,
        "fab_text_size_h": 1.0,
        "fab_text_size_v": 1.0,
        "fab_text_thickness": 0.15,
        "fab_text_upright": false,
        "other_line_width": 0.1,
        "other_text_italic": false,
        "other_text_size_h": 1.0,
        "other_text_size_v": 1.0,
        "other_text_thickness": 0.15,
        "other_text_upright": false,
        "pads": {
          "drill": 0.8,
          "height": 1.27,
          "width": 2.54
        },
        "silk_line_width": 0.1,
        "silk_text_italic": false,
        "silk_text_size_h": 1.0,
        "silk_text_size_v": 1.0,
        "silk_text_thickness": 0.1,
        "silk_text_upright": false,
        "zones": {
          "min_clearance": 0.1
        }
      },
      "diff_pair_dimensions": [
        {
          "gap": 0.0,
          "via_gap": 0.0,
          "width": 0.0
        }
      ],
      "drc_exclusions": [],
      "meta": {
        "version": 2
      },
      "rule_severities": {
        "annular_width": "error",
        "clearance": "error",
        "connection_width": "warning",
        "copper_edge_clearance": "error",
        "copper_sliver": "warning",
        "courtyards_overlap": "error",
        "creepage": "error",
        "diff_pair_gap_out_of_range": "error",
        "diff_pair_uncoupled_length_too_long": "error",
        "drill_out_of_range": "error",
        "duplicate_footprints": "warning",
        "extra_footprint": "warning",
        "footprint": "error",
        "footprint_filters_mismatch": "ignore",
        "footprint_symbol_mismatch": "warning",
        "footprint_type_mismatch": "ignore",
        "hole_clearance": "error",
        "hole_to_hole": "warning",
        "holes_co_located": "warning",
        "invalid_outline": "error",
        "isolated_copper": "warning",
        "item_on_disabled_layer": "error",
        "items_not_allowed": "error",
        "length_out_of_range": "error",
        "lib_footprint_issues": "warning",
        "lib_footprint_mismatch": "ignore",
        "malformed_courtyard": "error",
        "microvia_drill_out_of_range": "error",
        "mirrored_text_on_front_layer": "warning",
        "missing_courtyard": "warning",
        "missing_footprint": "warning",
        "net_conflict": "warning",
        "nonmirrored_text_on_back_layer": "warning",
        "npth_inside_courtyard": "ignore",
        "padstack": "warning",
        "pth_inside_courtyard": "ignore",
        "shorting_items": "error",
        "silk_edge_clearance": "warning",
        "silk_over_copper": "warning",
        "silk_overlap": "warning",
        "skew_out_of_range": "error",
        "solder_mask_bridge": "error",
        "starved_thermal": "error",
        "text_height": "warning",
        "text_on_edge_cuts": "error",
        "text_thickness": "warning",
        "through_hole_pad_without_hole": "error",
        "too_many_vias": "error",
        "track_angle": "error",
        "track_dangling": "warning",
        "track_segment_length": "error",
        "track_width": "error",
        "tracks_crossing": "error",
        "unconnected_items": "error",
        "unresolved_variable": "error",
        "via_dangling": "warning",
        "zones_intersect": "error"
      },
      "rules": {
        "max_error": 0.005,
        "min_clearance": 0.1,
        "min_connection": 0.1,
        "min_copper_edge_clearance": 0.4,
        "min_groove_width": 0.0,
        "min_hole_clearance": 0.2,
        "min_hole_to_hole": 0.2,
        "min_microvia_diameter": 0.25,
        "min_microvia_drill": 0.15,
        "min_resolved_spokes": 2,
        "min_silk_clearance": 0.0,
        "min_text_height": 0.5,
        "min_text_thickness": 0.08,
        "min_through_hole_diameter": 0.15,
        "min_track_width": 0.1,
        "min_via_annular_width": 0.075,
        "min_via_diameter": 0.25,
        "solder_mask_to_copper_clearance": 0.0,
        "use_height_for_length_calcs": true
      },
      "teardrop_options": [
        {
          "td_onpthpad": true,
          "td_onroundshapesonly": false,
          "td_onsmdpad": true,
          "td_ontrackend": false,
          "td_onvia": true
        }
      ],
      "teardrop_parameters": [
        {
          "td_allow_use_two_tracks": true,
          "td_curve_segcount": 0,
          "td_height_ratio": 1.0,
          "td_length_ratio": 0.5,
          "td_maxheight": 2.0,
          "td_maxlen": 1.0,
          "td_on_pad_in_zone": false,
          "td_target_name": "td_round_shape",
          "td_width_to_size_filter_ratio": 0.9
        },
        {
          "td_allow_use_two_tracks": true,
          "td_curve_segcount": 0,
          "td_height_ratio": 1.0,
          "td_length_ratio": 0.5,
          "td_maxheight": 2.0,
          "td_maxlen": 1.0,
          "td_on_pad_in_zone": false,
          "td_target_name": "td_rect_shape",
          "td_width_to_size_filter_ratio": 0.9
        },
        {
          "td_allow_use_two_tracks": true,
          "td_curve_segcount": 0,
          "td_height_ratio": 1.0,
          "td_length_ratio": 0.5,
          "td_maxheight": 2.0,
          "td_maxlen": 1.0,
          "td_on_pad_in_zone": false,
          "td_target_name": "td_track_end",
          "td_width_to_size_filter_ratio": 0.9
        }
      ],
      "track_widths": [
        0.0,
        0.1,
        0.25,
        0.5,
        0.75,
        1.0
      ],
      "tuning_pattern_settings": {
        "diff_pair_defaults": {
          "corner_radius_percentage": 80,
          "corner_style": 1,
          "max_amplitude": 1.0,
          "min_amplitude": 0.2,
          "single_sided": false,
          "spacing": 1.0
        },
        "diff_pair_skew_defaults": {
          "corner_radius_percentage": 80,
          "corner_style": 1,
          "max_amplitude": 1.0,
          "min_amplitude": 0.2,
          "single_sided": false,
          "spacing": 0.6
        },
        "single_track_defaults": {
          "corner_radius_percentage": 80,
          "corner_style": 1,
          "max_amplitude": 1.0,
          "min_amplitude": 0.2,
          "single_sided": false,
          "spacing": 0.6
        }
      },
      "via_dimensions": [
        {
          "diameter": 0.0,
          "drill": 0.0
        }
      ],
      "zones_allow_external_fillets": false
    },
    "ipc2581": {
      "dist": "",
      "distpn": "",
      "internal_id": "",
      "mfg": "",
      "mpn": ""
    },
    "layer_pairs": [],
    "layer_presets": [],
    "viewports": []
  },
  "boards": [],
  "cvpcb": {
    "equivalence_files": []
  },
  "erc": {
    "erc_exclusions": [],
    "meta": {
      "version": 0
    },
    "pin_map": [
      [
        0,
        0,
        0,
        0,
        0,
        0,
        1,
        0,
        0,
        0,
        0,
        2
      ],
      [
        0,
        2,
        0,
        1,
        0,
        0,
        1,
        0,
        2,
        2,
        2,
        2
      ],
      [
        0,
        0,
        0,
        0,
        0,
        0,
        1,
        0,
        1,
        0,
        1,
        2
      ],
      [
        0,
        1,
        0,
        0,
        0,
        0,
        1,
        1,
        2,
        1,
        1,
        2
      ],
      [
        0,
        0,
        0,
        0,
        0,
        0,
        1,
        0,
        0,
        0,
        0,
        2
      ],
      [
        0,
        0,
        0,
        0,
        0,
        0,
        0,
        0,
        0,
        0,
        0,
        2
      ],
      [
        1,
        1,
        1,
        1,
        1,
        0,
        1,
        1,
        1,
        1,
        1,
        2
      ],
      [
        0,
        0,
        0,
        1,
        0,
        0,
        1,
        0,
        0,
        0,
        0,
        2
      ],
      [
        0,
        2,
        1,
        2,
        0,
        0,
        1,
        0,
        2,
        2,
        2,
        2
      ],
      [
        0,
        2,
        0,
        1,
        0,
        0,
        1,
        0,
        2,
        0,
        0,
        2
      ],
      [
        0,
        2,
        1,
        1,
        0,
        0,
        1,
        0,
        2,
        0,
        0,
        2
      ],
      [
        2,
        2,
        2,
        2,
        2,
        2,
        2,
        2,
        2,
        2,
        2,
        2
      ]
    ],
    "rule_severities": {
      "bus_definition_conflict": "error",
      "bus_entry_needed": "error",
      "bus_to_bus_conflict": "error",
      "bus_to_net_conflict": "error",
      "different_unit_footprint": "error",
      "different_unit_net": "error",
      "duplicate_reference": "error",
      "duplicate_sheet_names": "error",
      "endpoint_off_grid": "warning",
      "extra_units": "error",
      "footprint_filter": "ignore",
      "footprint_link_issues": "warning",
      "four_way_junction": "ignore",
      "global_label_dangling": "warning",
      "hier_label_mismatch": "error",
      "label_dangling": "error",
      "label_multiple_wires": "warning",
      "lib_symbol_issues": "warning",
      "lib_symbol_mismatch": "warning",
      "missing_bidi_pin": "warning",
      "missing_input_pin": "warning",
      "missing_power_pin": "error",
      "missing_unit": "warning",
      "multiple_net_names": "warning",
      "net_not_bus_member": "warning",
      "no_connect_connected": "warning",
      "no_connect_dangling": "warning",
      "pin_not_connected": "error",
      "pin_not_driven": "error",
      "pin_to_pin": "ignore",
      "power_pin_not_driven": "error",
      "same_local_global_label": "warning",
      "similar_label_and_power": "warning",
      "similar_labels": "warning",
      "similar_power": "warning",
      "simulation_model_issue": "ignore",
      "single_global_label": "error",
      "unannotated": "error",
      "unconnected_wire_endpoint": "warning",
      "undefined_netclass": "error",
      "unit_value_mismatch": "error",
      "unresolved_variable": "error",
      "wire_dangling": "error"
    }
  },
  "libraries": {
    "pinned_footprint_libs": [],
    "pinned_symbol_libs": []
  },
  "meta": {
    "filename": "thunderbolt-to-10gbe-adapter.kicad_pro",
    "version": 3
  },
  "net_settings": {
    "classes": [
      {
        "bus_width": 12,
        "clearance": 0.1,
        "diff_pair_gap": 0.1,
        "diff_pair_via_gap": 0.25,
        "diff_pair_width": 0.1,
        "line_style": 0,
        "microvia_diameter": 0.3,
        "microvia_drill": 0.1,
        "name": "Default",
        "pcb_color": "rgba(0, 0, 0, 0.000)",
        "priority": 2147483647,
        "schematic_color": "rgba(0, 0, 0, 0.000)",
        "track_width": 0.1,
        "via_diameter": 0.45,
        "via_drill": 0.1,
        "wire_width": 6
      },
      {
        "clearance": 0.1,
        "diff_pair_gap": 0.2,
        "diff_pair_width": 0.15,
        "name": "100Ohm-diff_10GbE",
        "pcb_color": "rgb(198, 255, 0)",
        "priority": 0,
        "schematic_color": "rgba(0, 0, 0, 0.000)",
        "track_width": 0.15,
        "via_diameter": 0.45,
        "via_drill": 0.1
      },
      {
        "bus_width": 12,
        "clearance": 0.1,
        "diff_pair_gap": 1.0,
        "diff_pair_width": 1.0,
        "line_style": 0,
        "microvia_diameter": 0.3,
        "microvia_drill": 0.1,
        "name": "85Ohm-diff_PCIe",
        "pcb_color": "rgb(255, 0, 250)",
        "priority": 1,
        "schematic_color": "rgba(0, 0, 0, 0.000)",
        "track_width": 0.2,
        "via_diameter": 0.45,
        "via_drill": 0.1,
        "wire_width": 6
      },
      {
        "bus_width": 12,
        "clearance": 0.1,
        "diff_pair_gap": 1.0,
        "diff_pair_width": 1.0,
        "line_style": 0,
        "microvia_diameter": 0.3,
        "microvia_drill": 0.1,
        "name": "85Ohm-diff_USB4",
        "pcb_color": "rgb(0, 201, 255)",
        "priority": 2,
        "schematic_color": "rgba(0, 0, 0, 0.000)",
        "track_width": 0.2,
        "via_diameter": 0.45,
        "via_drill": 0.1,
        "wire_width": 6
      },
      {
        "bus_width": 12,
        "clearance": 0.1,
        "diff_pair_gap": 1.0,
        "diff_pair_width": 1.0,
        "line_style": 0,
        "microvia_diameter": 0.3,
        "microvia_drill": 0.1,
        "name": "90Ohm-diff_USB2",
        "pcb_color": "rgb(31, 0, 255)",
        "priority": 3,
        "schematic_color": "rgba(0, 0, 0, 0.000)",
        "track_width": 0.15,
        "via_diameter": 0.45,
        "via_drill": 0.1,
        "wire_width": 6
      }
    ],
    "meta": {
      "version": 4
    },
    "net_colors": null,
    "netclass_assignments": {
      "+1V88": [
        "PWR"
      ],
      "+3V3": [
        "PWR"
      ],
      "/2xRJ45/Ethernet_P0.D1+": [
        "100Ohm-diff_10GbE"
      ],
      "/2xRJ45/Ethernet_P0.D1-": [
        "100Ohm-diff_10GbE"
      ],
      "/2xRJ45/Ethernet_P0.D2+": [
        "100Ohm-diff_10GbE"
      ],
      "/2xRJ45/Ethernet_P0.D2-": [
        "100Ohm-diff_10GbE"
      ],
      "/2xRJ45/Ethernet_P0.D3+": [
        "100Ohm-diff_10GbE"
      ],
      "/2xRJ45/Ethernet_P0.D3-": [
        "100Ohm-diff_10GbE"
      ],
      "/2xRJ45/Ethernet_P0.D4+": [
        "100Ohm-diff_10GbE"
      ],
      "/2xRJ45/Ethernet_P0.D4-": [
        "100Ohm-diff_10GbE"
      ],
      "/2xRJ45/Ethernet_P0{10GbE}": [
        "100Ohm-diff_10GbE"
      ],
      "/2xRJ45/Ethernet_P1.D1+": [
        "100Ohm-diff_10GbE"
      ],
      "/2xRJ45/Ethernet_P1.D1-": [
        "100Ohm-diff_10GbE"
      ],
      "/2xRJ45/Ethernet_P1.D2+": [
        "100Ohm-diff_10GbE"
      ],
      "/2xRJ45/Ethernet_P1.D2-": [
        "100Ohm-diff_10GbE"
      ],
      "/2xRJ45/Ethernet_P1.D3+": [
        "100Ohm-diff_10GbE"
      ],
      "/2xRJ45/Ethernet_P1.D3-": [
        "100Ohm-diff_10GbE"
      ],
      "/2xRJ45/Ethernet_P1.D4+": [
        "100Ohm-diff_10GbE"
      ],
      "/2xRJ45/Ethernet_P1.D4-": [
        "100Ohm-diff_10GbE"
      ],
      "/2xRJ45/Ethernet_P1{10GbE}": [
        "100Ohm-diff_10GbE"
      ],
      "/OCuLink/PCIe_{x4}.RX0+": [
        "85Ohm-diff_PCIe"
      ],
      "/OCuLink/PCIe_{x4}.RX0-": [
        "85Ohm-diff_PCIe"
      ],
      "/OCuLink/PCIe_{x4}.RX1+": [
        "85Ohm-diff_PCIe"
      ],
      "/OCuLink/PCIe_{x4}.RX1-": [
        "85Ohm-diff_PCIe"
      ],
      "/OCuLink/PCIe_{x4}.RX2+": [
        "85Ohm-diff_PCIe"
      ],
      "/OCuLink/PCIe_{x4}.RX2-": [
        "85Ohm-diff_PCIe"
      ],
      "/OCuLink/PCIe_{x4}.RX3+": [
        "85Ohm-diff_PCIe"
      ],
      "/OCuLink/PCIe_{x4}.RX3-": [
        "85Ohm-diff_PCIe"
      ],
      "/OCuLink/PCIe_{x4}.TX0+": [
        "85Ohm-diff_PCIe"
      ],
      "/OCuLink/PCIe_{x4}.TX0-": [
        "85Ohm-diff_PCIe"
      ],
      "/OCuLink/PCIe_{x4}.TX1+": [
        "85Ohm-diff_PCIe"
      ],
      "/OCuLink/PCIe_{x4}.TX1-": [
        "85Ohm-diff_PCIe"
      ],
      "/OCuLink/PCIe_{x4}.TX2+": [
        "85Ohm-diff_PCIe"
      ],
      "/OCuLink/PCIe_{x4}.TX2-": [
        "85Ohm-diff_PCIe"
      ],
      "/OCuLink/PCIe_{x4}.TX3+": [
        "85Ohm-diff_PCIe"
      ],
      "/OCuLink/PCIe_{x4}.TX3-": [
        "85Ohm-diff_PCIe"
      ],
      "/OCuLink/PCIe_{x4}{PCIe}": [
        "85Ohm-diff_PCIe"
      ],
      "/OCuLink/REFCLK.+": [
        "85Ohm-diff_PCIe"
      ],
      "/OCuLink/REFCLK.-": [
        "85Ohm-diff_PCIe"
      ],
      "/OCuLink/REFCLK{CLK}": [
        "85Ohm-diff_PCIe"
      ],
      "/PD and TB DC-DC/AUX.+": [
        "85Ohm-diff_USB4"
      ],
      "/PD and TB DC-DC/AUX.-": [
        "85Ohm-diff_USB4"
      ],
      "/PD and TB DC-DC/USB3.CC1": [
        "85Ohm-diff_USB4",
        "90Ohm-diff_USB2"
      ],
      "/PD and TB DC-DC/USB3.CC2": [
        "85Ohm-diff_USB4",
        "90Ohm-diff_USB2"
      ],
      "/PD and TB DC-DC/USB3.D_A_N": [
        "90Ohm-diff_USB2"
      ],
      "/PD and TB DC-DC/USB3.D_A_P": [
        "90Ohm-diff_USB2"
      ],
      "/PD and TB DC-DC/USB3.D_B_N": [
        "90Ohm-diff_USB2"
      ],
      "/PD and TB DC-DC/USB3.D_B_P": [
        "90Ohm-diff_USB2"
      ],
      "/PD and TB DC-DC/USB3.RX0_N": [
        "85Ohm-diff_USB4"
      ],
      "/PD and TB DC-DC/USB3.RX0_P": [
        "85Ohm-diff_USB4"
      ],
      "/PD and TB DC-DC/USB3.RX1_N": [
        "85Ohm-diff_USB4"
      ],
      "/PD and TB DC-DC/USB3.RX1_P": [
        "85Ohm-diff_USB4"
      ],
      "/PD and TB DC-DC/USB3.SBU1": [
        "85Ohm-diff_USB4",
        "90Ohm-diff_USB2"
      ],
      "/PD and TB DC-DC/USB3.SBU2": [
        "85Ohm-diff_USB4",
        "90Ohm-diff_USB2"
      ],
      "/PD and TB DC-DC/USB3.TX0_N": [
        "85Ohm-diff_USB4"
      ],
      "/PD and TB DC-DC/USB3.TX0_P": [
        "85Ohm-diff_USB4"
      ],
      "/PD and TB DC-DC/USB3.TX1_N": [
        "85Ohm-diff_USB4"
      ],
      "/PD and TB DC-DC/USB3.TX1_P": [
        "85Ohm-diff_USB4"
      ],
      "/PD and TB DC-DC/USB3{USB_3.0}": [
        "85Ohm-diff_USB4",
        "90Ohm-diff_USB2"
      ],
      "/PD and TB DC-DC/USB_RP.D+": [
        "90Ohm-diff_USB2"
      ],
      "/PD and TB DC-DC/USB_RP.D-": [
        "90Ohm-diff_USB2"
      ],
      "/PD and TB DC-DC/USB_RP.USB_RP_N": [
        "90Ohm-diff_USB2"
      ],
      "/PD and TB DC-DC/USB_RP.USB_RP_P": [
        "90Ohm-diff_USB2"
      ],
      "/TB Controller/PA_AUX_N": [
        "85Ohm-diff_USB4"
      ],
      "/TB Controller/PA_AUX_P": [
        "85Ohm-diff_USB4"
      ],
      "/TB Controller/PA_TX0_N": [
        "85Ohm-diff_USB4"
      ],
      "/TB Controller/PA_TX0_P": [
        "85Ohm-diff_USB4"
      ],
      "/TB Controller/PA_TX1_N": [
        "85Ohm-diff_USB4"
      ],
      "/TB Controller/PA_TX1_P": [
        "85Ohm-diff_USB4"
      ],
      "/TB Controller/PCIE_CLK_JHL_N": [
        "85Ohm-diff_PCIe"
      ],
      "/TB Controller/PCIE_CLK_JHL_P": [
        "85Ohm-diff_PCIe"
      ],
      "/TB Controller/PCIe_{x4}.RX0+": [
        "85Ohm-diff_PCIe"
      ],
      "/TB Controller/PCIe_{x4}.RX0-": [
        "85Ohm-diff_PCIe"
      ],
      "/TB Controller/PCIe_{x4}.RX1+": [
        "85Ohm-diff_PCIe"
      ],
      "/TB Controller/PCIe_{x4}.RX1-": [
        "85Ohm-diff_PCIe"
      ],
      "/TB Controller/PCIe_{x4}.RX2+": [
        "85Ohm-diff_PCIe"
      ],
      "/TB Controller/PCIe_{x4}.RX2-": [
        "85Ohm-diff_PCIe"
      ],
      "/TB Controller/PCIe_{x4}.RX3+": [
        "85Ohm-diff_PCIe"
      ],
      "/TB Controller/PCIe_{x4}.RX3-": [
        "85Ohm-diff_PCIe"
      ],
      "/TB Controller/PCIe_{x4}.TX0+": [
        "85Ohm-diff_PCIe"
      ],
      "/TB Controller/PCIe_{x4}.TX0-": [
        "85Ohm-diff_PCIe"
      ],
      "/TB Controller/PCIe_{x4}.TX1+": [
        "85Ohm-diff_PCIe"
      ],
      "/TB Controller/PCIe_{x4}.TX1-": [
        "85Ohm-diff_PCIe"
      ],
      "/TB Controller/PCIe_{x4}.TX2+": [
        "85Ohm-diff_PCIe"
      ],
      "/TB Controller/PCIe_{x4}.TX2-": [
        "85Ohm-diff_PCIe"
      ],
      "/TB Controller/PCIe_{x4}.TX3+": [
        "85Ohm-diff_PCIe"
      ],
      "/TB Controller/PCIe_{x4}.TX3-": [
        "85Ohm-diff_PCIe"
      ],
      "/TB Controller/PCIe_{x4}{PCIe}": [
        "85Ohm-diff_PCIe"
      ],
      "/TB Controller/PCIex4.RX0+": [
        "85Ohm-diff_PCIe"
      ],
      "/TB Controller/PCIex4.RX0-": [
        "85Ohm-diff_PCIe"
      ],
      "/TB Controller/PCIex4.RX1+": [
        "85Ohm-diff_PCIe"
      ],
      "/TB Controller/PCIex4.RX1-": [
        "85Ohm-diff_PCIe"
      ],
      "/TB Controller/PCIex4.RX2+": [
        "85Ohm-diff_PCIe"
      ],
      "/TB Controller/PCIex4.RX2-": [
        "85Ohm-diff_PCIe"
      ],
      "/TB Controller/PCIex4.RX3+": [
        "85Ohm-diff_PCIe"
      ],
      "/TB Controller/PCIex4.RX3-": [
        "85Ohm-diff_PCIe"
      ],
      "/TB Controller/PCIex4.TX0+": [
        "85Ohm-diff_PCIe"
      ],
      "/TB Controller/PCIex4.TX0-": [
        "85Ohm-diff_PCIe"
      ],
      "/TB Controller/PCIex4.TX1+": [
        "85Ohm-diff_PCIe"
      ],
      "/TB Controller/PCIex4.TX1-": [
        "85Ohm-diff_PCIe"
      ],
      "/TB Controller/PCIex4.TX2+": [
        "85Ohm-diff_PCIe"
      ],
      "/TB Controller/PCIex4.TX2-": [
        "85Ohm-diff_PCIe"
      ],
      "/TB Controller/PCIex4.TX3+": [
        "85Ohm-diff_PCIe"
      ],
      "/TB Controller/PCIex4.TX3-": [
        "85Ohm-diff_PCIe"
      ],
      "/TB Controller/PCIex4{PCIe}": [
        "85Ohm-diff_PCIe"
      ],
      "/TB Controller/PCIex4}.RX0+": [
        "85Ohm-diff_PCIe"
      ],
      "/TB Controller/PCIex4}.RX0-": [
        "85Ohm-diff_PCIe"
      ],
      "/TB Controller/PCIex4}.RX1+": [
        "85Ohm-diff_PCIe"
      ],
      "/TB Controller/PCIex4}.RX1-": [
        "85Ohm-diff_PCIe"
      ],
      "/TB Controller/PCIex4}.RX2+": [
        "85Ohm-diff_PCIe"
      ],
      "/TB Controller/PCIex4}.RX2-": [
        "85Ohm-diff_PCIe"
      ],
      "/TB Controller/PCIex4}.RX3+": [
        "85Ohm-diff_PCIe"
      ],
      "/TB Controller/PCIex4}.RX3-": [
        "85Ohm-diff_PCIe"
      ],
      "/TB Controller/PCIex4}.TX0+": [
        "85Ohm-diff_PCIe"
      ],
      "/TB Controller/PCIex4}.TX0-": [
        "85Ohm-diff_PCIe"
      ],
      "/TB Controller/PCIex4}.TX1+": [
        "85Ohm-diff_PCIe"
      ],
      "/TB Controller/PCIex4}.TX1-": [
        "85Ohm-diff_PCIe"
      ],
      "/TB Controller/PCIex4}.TX2+": [
        "85Ohm-diff_PCIe"
      ],
      "/TB Controller/PCIex4}.TX2-": [
        "85Ohm-diff_PCIe"
      ],
      "/TB Controller/PCIex4}.TX3+": [
        "85Ohm-diff_PCIe"
      ],
      "/TB Controller/PCIex4}.TX3-": [
        "85Ohm-diff_PCIe"
      ],
      "/TB Controller/REFCLK.+": [
        "85Ohm-diff_PCIe"
      ],
      "/TB Controller/REFCLK.-": [
        "85Ohm-diff_PCIe"
      ],
      "/TB Controller/REFCLK{CLK}": [
        "85Ohm-diff_PCIe"
      ],
      "/TB Controller/TB_PCIE_TX0_N": [
        "85Ohm-diff_PCIe"
      ],
      "/TB Controller/TB_PCIE_TX0_P": [
        "85Ohm-diff_PCIe"
      ],
      "/TB Controller/TB_PCIE_TX1_N": [
        "85Ohm-diff_PCIe"
      ],
      "/TB Controller/TB_PCIE_TX1_P": [
        "85Ohm-diff_PCIe"
      ],
      "/TB Controller/TB_PCIE_TX2_N": [
        "85Ohm-diff_PCIe"
      ],
      "/TB Controller/TB_PCIE_TX2_P": [
        "85Ohm-diff_PCIe"
      ],
      "/TB Controller/TB_PCIE_TX3_N": [
        "85Ohm-diff_PCIe"
      ],
      "/TB Controller/TB_PCIE_TX3_P": [
        "85Ohm-diff_PCIe"
      ],
      "/X710-AT2 10GbE/25MHZ_OSC.+": [
        "85Ohm-diff_PCIe"
      ],
      "/X710-AT2 10GbE/25MHZ_OSC.-": [
        "85Ohm-diff_PCIe"
      ],
      "/X710-AT2 10GbE/25MHZ_OSC_AC.+": [
        "85Ohm-diff_PCIe"
      ],
      "/X710-AT2 10GbE/25MHZ_OSC_AC.-": [
        "85Ohm-diff_PCIe"
      ],
      "/X710-AT2 10GbE/25MHZ_OSC_R.+": [
        "85Ohm-diff_PCIe"
      ],
      "/X710-AT2 10GbE/25MHZ_OSC_R.-": [
        "85Ohm-diff_PCIe"
      ],
      "/X710-AT2 PCIe/CLK+": [
        "85Ohm-diff_PCIe"
      ],
      "/X710-AT2 PCIe/CLK-": [
        "85Ohm-diff_PCIe"
      ],
      "/X710-AT2 PCIe/GEN_CLK+": [
        "85Ohm-diff_PCIe"
      ],
      "/X710-AT2 PCIe/GEN_CLK-": [
        "85Ohm-diff_PCIe"
      ],
      "/X710-AT2 PCIe/GEN_F_CLK+": [
        "85Ohm-diff_PCIe"
      ],
      "/X710-AT2 PCIe/GEN_F_CLK-": [
        "85Ohm-diff_PCIe"
      ],
      "/X710-AT2 PCIe/PCIe_{x4}.RX0+": [
        "85Ohm-diff_PCIe"
      ],
      "/X710-AT2 PCIe/PCIe_{x4}.RX0-": [
        "85Ohm-diff_PCIe"
      ],
      "/X710-AT2 PCIe/PCIe_{x4}.RX1+": [
        "85Ohm-diff_PCIe"
      ],
      "/X710-AT2 PCIe/PCIe_{x4}.RX1-": [
        "85Ohm-diff_PCIe"
      ],
      "/X710-AT2 PCIe/PCIe_{x4}.RX2+": [
        "85Ohm-diff_PCIe"
      ],
      "/X710-AT2 PCIe/PCIe_{x4}.RX2-": [
        "85Ohm-diff_PCIe"
      ],
      "/X710-AT2 PCIe/PCIe_{x4}.RX3+": [
        "85Ohm-diff_PCIe"
      ],
      "/X710-AT2 PCIe/PCIe_{x4}.RX3-": [
        "85Ohm-diff_PCIe"
      ],
      "/X710-AT2 PCIe/PCIe_{x4}.TX0+": [
        "85Ohm-diff_PCIe"
      ],
      "/X710-AT2 PCIe/PCIe_{x4}.TX0-": [
        "85Ohm-diff_PCIe"
      ],
      "/X710-AT2 PCIe/PCIe_{x4}.TX1+": [
        "85Ohm-diff_PCIe"
      ],
      "/X710-AT2 PCIe/PCIe_{x4}.TX1-": [
        "85Ohm-diff_PCIe"
      ],
      "/X710-AT2 PCIe/PCIe_{x4}.TX2+": [
        "85Ohm-diff_PCIe"
      ],
      "/X710-AT2 PCIe/PCIe_{x4}.TX2-": [
        "85Ohm-diff_PCIe"
      ],
      "/X710-AT2 PCIe/PCIe_{x4}.TX3+": [
        "85Ohm-diff_PCIe"
      ],
      "/X710-AT2 PCIe/PCIe_{x4}.TX3-": [
        "85Ohm-diff_PCIe"
      ],
      "/X710-AT2 PCIe/PCIe_{x4}_AC.TX0+": [
        "85Ohm-diff_PCIe"
      ],
      "/X710-AT2 PCIe/PCIe_{x4}_AC.TX0-": [
        "85Ohm-diff_PCIe"
      ],
      "/X710-AT2 PCIe/PCIe_{x4}_AC.TX1+": [
        "85Ohm-diff_PCIe"
      ],
      "/X710-AT2 PCIe/PCIe_{x4}_AC.TX1-": [
        "85Ohm-diff_PCIe"
      ],
      "/X710-AT2 PCIe/PCIe_{x4}_AC.TX2+": [
        "85Ohm-diff_PCIe"
      ],
      "/X710-AT2 PCIe/PCIe_{x4}_AC.TX2-": [
        "85Ohm-diff_PCIe"
      ],
      "/X710-AT2 PCIe/PCIe_{x4}_AC.TX3+": [
        "85Ohm-diff_PCIe"
      ],
      "/X710-AT2 PCIe/PCIe_{x4}_AC.TX3-": [
        "85Ohm-diff_PCIe"
      ],
      "/X710-AT2 PCIe/PCIe_{x4}{PCIe}": [
        "85Ohm-diff_PCIe"
      ],
      "/X710-AT2 PCIe/REFCLK.+": [
        "85Ohm-diff_PCIe"
      ],
      "/X710-AT2 PCIe/REFCLK.-": [
        "85Ohm-diff_PCIe"
      ],
      "/X710-AT2 PCIe/REFCLK{CLK}": [
        "85Ohm-diff_PCIe"
      ],
      "5V_X710": [
        "PWR"
      ],
      "AVDDH": [
        "PWR"
      ],
      "DVDD": [
        "PWR"
      ],
      "P0_AVDDL": [
        "PWR"
      ],
      "P1_AVDDL": [
        "PWR"
      ],
      "PLL_VDD": [
        "PWR"
      ],
      "VCC": [
        "PWR"
      ],
      "VCCA": [
        "PWR"
      ],
      "VCCD": [
        "PWR"
      ],
      "XFI_PVDD": [
        "PWR"
      ],
      "XFI_VDD": [
        "PWR"
      ],
      "XGB_AVDDH": [
        "PWR"
      ]
    },
    "netclass_patterns": []
  },
  "pcbnew": {
    "last_paths": {
      "gencad": "",
      "idf": "",
      "netlist": "",
      "plot": "",
      "pos_files": "",
      "specctra_dsn": "",
      "step": "",
      "svg": "",
      "vrml": ""
    },
    "page_layout_descr_file": ""
  },
  "schematic": {
    "annotate_start_num": 0,
    "bom_export_filename": "${PROJECTNAME}.csv",
    "bom_fmt_presets": [],
    "bom_fmt_settings": {
      "field_delimiter": ",",
      "keep_line_breaks": false,
      "keep_tabs": false,
      "name": "CSV",
      "ref_delimiter": ",",
      "ref_range_delimiter": "",
      "string_delimiter": "\""
    },
    "bom_presets": [],
    "bom_settings": {
      "exclude_dnp": false,
      "fields_ordered": [
        {
          "group_by": false,
          "label": "Reference",
          "name": "Reference",
          "show": true
        },
        {
          "group_by": false,
          "label": "Qty",
          "name": "${QUANTITY}",
          "show": true
        },
        {
          "group_by": true,
          "label": "Value",
          "name": "Value",
          "show": true
        },
        {
          "group_by": true,
          "label": "DNP",
          "name": "${DNP}",
          "show": true
        },
        {
          "group_by": true,
          "label": "Exclude from BOM",
          "name": "${EXCLUDE_FROM_BOM}",
          "show": true
        },
        {
          "group_by": true,
          "label": "Exclude from Board",
          "name": "${EXCLUDE_FROM_BOARD}",
          "show": true
        },
        {
          "group_by": true,
          "label": "Footprint",
          "name": "Footprint",
          "show": true
        },
        {
          "group_by": false,
          "label": "Datasheet",
          "name": "Datasheet",
          "show": true
        }
      ],
      "filter_string": "",
      "group_symbols": true,
      "include_excluded_from_bom": true,
      "name": "Default Editing",
      "sort_asc": true,
      "sort_field": "Reference"
    },
    "connection_grid_size": 50.0,
    "drawing": {
      "dashed_lines_dash_length_ratio": 12.0,
      "dashed_lines_gap_length_ratio": 3.0,
      "default_line_thickness": 6.0,
      "default_text_size": 50.0,
      "field_names": [],
      "intersheets_ref_own_page": false,
      "intersheets_ref_prefix": "",
      "intersheets_ref_short": false,
      "intersheets_ref_show": false,
      "intersheets_ref_suffix": "",
      "junction_size_choice": 3,
      "label_size_ratio": 0.375,
      "operating_point_overlay_i_precision": 3,
      "operating_point_overlay_i_range": "~A",
      "operating_point_overlay_v_precision": 3,
      "operating_point_overlay_v_range": "~V",
      "overbar_offset_ratio": 1.23,
      "pin_symbol_size": 25.0,
      "text_offset_ratio": 0.15
    },
    "legacy_lib_dir": "",
    "legacy_lib_list": [],
    "meta": {
      "version": 1
    },
    "net_format_name": "",
    "page_layout_descr_file": "",
    "plot_directory": "",
    "space_save_all_events": true,
    "spice_current_sheet_as_root": false,
    "spice_external_command": "spice \"%I\"",
    "spice_model_current_sheet_as_root": true,
    "spice_save_all_currents": false,
    "spice_save_all_dissipations": false,
    "spice_save_all_voltages": false,
    "subpart_first_id": 65,
    "subpart_id_separator": 0
  },
  "sheets": [
    [
      "",
      "Root"
    ],
    [
      "",
      "USB-C connector"
    ],
    [
      "",
      "PD and TB DC-DC"
    ],
    [
      "",
      "TB Controller"
    ],
    [
      "",
      "TB Controller - Power"
    ],
    [
      "",
      "TB flash memory"
    ],
    [
      "",
      "X710 DCDC converters"
    ],
    [
      "",
      "X710-AT2 power"
    ],
    [
      "",
      "X710-AT2 PCIe"
    ],
    [
      "",
      "X710-AT2 RSVD"
    ],
    [
      "",
      "X710-AT2 Misc"
    ],
    [
      "",
      "X710-AT2 10GbE"
    ],
    [
      "",
      "2xRJ45"
    ],
    [
      "",
      "Fan controller"
    ],
    [
      "",
      "X710 flash memory"
    ],
    [
      "",
      "Power input"
    ]
  ],
  "text_variables": {}
}
